(kicad_pcb
	(version 20260206)
	(generator "pcbnew")
	(generator_version "10.0")
	(general
		(thickness 1.6)
		(legacy_teardrops no)
	)
	(paper "A4")
	(title_block
		(title "03242023_DA0F0TMBIJ0_F0T_Motherboard_J_brd_V01_OCP.brd")
		(comment 1 "Grand Teton / footprints 4235-4241 of 6105")
	)
	(layers
		(0 "F.Cu" signal "TOP")
		(4 "In1.Cu" signal "GND")
		(6 "In2.Cu" signal "IN1")
		(8 "In3.Cu" signal "GND1")
		(10 "In4.Cu" signal "IN2")
		(12 "In5.Cu" signal "GND2")
		(14 "In6.Cu" signal "IN3")
		(16 "In7.Cu" signal "GND3")
		(18 "In8.Cu" signal "VCC")
		(20 "In9.Cu" signal "VCC1")
		(22 "In10.Cu" signal "GND4")
		(24 "In11.Cu" signal "IN4")
		(26 "In12.Cu" signal "GND5")
		(28 "In13.Cu" signal "IN5")
		(30 "In14.Cu" signal "GND6")
		(32 "In15.Cu" signal "IN6")
		(34 "In16.Cu" signal "GND7")
		(2 "B.Cu" signal "BOTTOM")
		(9 "F.Adhes" user "F.Adhesive")
		(11 "B.Adhes" user "B.Adhesive")
		(13 "F.Paste" user "Package Geometry/Pastemask Top")
		(15 "B.Paste" user "Package Geometry/Pastemask Bottom")
		(5 "F.SilkS" user "Ref Des/Silkscreen Top")
		(7 "B.SilkS" user "Ref Des/Silkscreen Bottom")
		(1 "F.Mask" user "Board Geometry/Soldermask Top")
		(3 "B.Mask" user "Board Geometry/Soldermask Bottom")
		(17 "Dwgs.User" user "User.Drawings")
		(19 "Cmts.User" user "User.Comments")
		(21 "Eco1.User" user "User.Eco1")
		(23 "Eco2.User" user "User.Eco2")
		(25 "Edge.Cuts" user "Board Geometry/Outline")
		(27 "Margin" user)
		(31 "F.CrtYd" user "Package Geometry/Place Bound Top")
		(29 "B.CrtYd" user "Package Geometry/Place Bound Bottom")
		(35 "F.Fab" user "Ref Des/Assembly Top")
		(33 "B.Fab" user "Ref Des/Assembly Bottom")
	)
	(footprint ""
		(layer "B.Cu")
		(at 359.56113 -360.847386)
		(property "Reference" "PR166"
			(at 0 0 0)
			(layer "B.SilkS")
			(hide yes)
			(effects
				(font
					(size 1.27 1.27)
				)
				(justify mirror)
			)
		)
		(property "Value" ""
			(at 0 0 0)
			(layer "B.Fab")
			(effects
				(font
					(size 1.27 1.27)
				)
				(justify mirror)
			)
		)
		(duplicate_pad_numbers_are_jumpers no)
		(fp_line
			(start -0.7874 -0.4064)
			(end -0.7874 0.4064)
			(stroke
				(width 0.1524)
				(type default)
			)
			(layer "B.SilkS")
		)
		(fp_line
			(start -0.7874 0.4064)
			(end 0.7874 0.4064)
			(stroke
				(width 0.1524)
				(type default)
			)
			(layer "B.SilkS")
		)
		(fp_line
			(start 0.7874 -0.4064)
			(end -0.7874 -0.4064)
			(stroke
				(width 0.1524)
				(type default)
			)
			(layer "B.SilkS")
		)
		(fp_line
			(start 0.7874 0.4064)
			(end 0.7874 -0.4064)
			(stroke
				(width 0.1524)
				(type default)
			)
			(layer "B.SilkS")
		)
		(fp_line
			(start -0.67945 -0.3048)
			(end -0.67945 0.3048)
			(stroke
				(width 0.1)
				(type default)
			)
			(layer "B.Fab")
		)
		(fp_line
			(start -0.67945 0.3048)
			(end -0.120396 0.3048)
			(stroke
				(width 0.1)
				(type default)
			)
			(layer "B.Fab")
		)
		(fp_line
			(start -0.12065 -0.3048)
			(end -0.67945 -0.3048)
			(stroke
				(width 0.1)
				(type default)
			)
			(layer "B.Fab")
		)
		(fp_line
			(start -0.12065 -0.2794)
			(end -0.12065 -0.3048)
			(stroke
				(width 0.1)
				(type default)
			)
			(layer "B.Fab")
		)
		(fp_line
			(start -0.120396 0.2794)
			(end 0.12065 0.2794)
			(stroke
				(width 0.1)
				(type default)
			)
			(layer "B.Fab")
		)
		(fp_line
			(start -0.120396 0.3048)
			(end -0.120396 0.2794)
			(stroke
				(width 0.1)
				(type default)
			)
			(layer "B.Fab")
		)
		(fp_line
			(start 0.12065 -0.305054)
			(end 0.12065 -0.2794)
			(stroke
				(width 0.1)
				(type default)
			)
			(layer "B.Fab")
		)
		(fp_line
			(start 0.12065 -0.2794)
			(end -0.12065 -0.2794)
			(stroke
				(width 0.1)
				(type default)
			)
			(layer "B.Fab")
		)
		(fp_line
			(start 0.12065 0.2794)
			(end 0.12065 0.3048)
			(stroke
				(width 0.1)
				(type default)
			)
			(layer "B.Fab")
		)
		(fp_line
			(start 0.12065 0.3048)
			(end 0.67945 0.3048)
			(stroke
				(width 0.1)
				(type default)
			)
			(layer "B.Fab")
		)
		(fp_line
			(start 0.67945 -0.305054)
			(end 0.12065 -0.305054)
			(stroke
				(width 0.1)
				(type default)
			)
			(layer "B.Fab")
		)
		(fp_line
			(start 0.67945 0.3048)
			(end 0.67945 -0.305054)
			(stroke
				(width 0.1)
				(type default)
			)
			(layer "B.Fab")
		)
		(pad "1" smd circle
			(at 0.40005 0 180)
			(size 0 0)
			(layers "B.Cu" "B.Mask" "B.Paste")
			(net "PVCCIN_CPU0_VIN_CSNIN")
		)
		(pad "2" smd circle
			(at -0.40005 0 180)
			(size 0 0)
			(layers "B.Cu" "B.Mask" "B.Paste")
			(net "GND")
		)
	)
	(footprint ""
		(layer "B.Cu")
		(at 416.02914 -167.56507)
		(property "Reference" "PC195_P0_1"
			(at 0 0 0)
			(layer "B.SilkS")
			(hide yes)
			(effects
				(font
					(size 1.27 1.27)
				)
				(justify mirror)
			)
		)
		(property "Value" ""
			(at 0 0 0)
			(layer "B.Fab")
			(effects
				(font
					(size 1.27 1.27)
				)
				(justify mirror)
			)
		)
		(duplicate_pad_numbers_are_jumpers no)
		(fp_line
			(start -1.524 -0.762)
			(end -1.524 0.762)
			(stroke
				(width 0.1524)
				(type default)
			)
			(layer "B.SilkS")
		)
		(fp_line
			(start -1.524 0.762)
			(end 1.524 0.762)
			(stroke
				(width 0.1524)
				(type default)
			)
			(layer "B.SilkS")
		)
		(fp_line
			(start 1.524 -0.762)
			(end -1.524 -0.762)
			(stroke
				(width 0.1524)
				(type default)
			)
			(layer "B.SilkS")
		)
		(fp_line
			(start 1.524 0.762)
			(end 1.524 -0.762)
			(stroke
				(width 0.1524)
				(type default)
			)
			(layer "B.SilkS")
		)
		(fp_line
			(start -1.1049 -0.724916)
			(end 1.1049 -0.724916)
			(stroke
				(width 0.1)
				(type default)
			)
			(layer "B.Fab")
		)
		(fp_line
			(start -1.1049 0.724916)
			(end -1.1049 -0.724916)
			(stroke
				(width 0.1)
				(type default)
			)
			(layer "B.Fab")
		)
		(fp_line
			(start 1.1049 -0.724916)
			(end 1.1049 0.724916)
			(stroke
				(width 0.1)
				(type default)
			)
			(layer "B.Fab")
		)
		(fp_line
			(start 1.1049 0.724916)
			(end -1.1049 0.724916)
			(stroke
				(width 0.1)
				(type default)
			)
			(layer "B.Fab")
		)
		(pad "1" smd rect
			(at 0.889 0)
			(size 1.016 1.27)
			(layers "B.Cu" "B.Mask" "B.Paste")
			(net "SW_P12V_PVCCINFAON_CPU0_FLT")
		)
		(pad "2" smd rect
			(at -0.889 0)
			(size 1.016 1.27)
			(layers "B.Cu" "B.Mask" "B.Paste")
			(net "GND")
		)
	)
	(footprint ""
		(layer "B.Cu")
		(at 127.257302 -338.098892 -90)
		(property "Reference" "PR294"
			(at 0 0 90)
			(layer "B.SilkS")
			(hide yes)
			(effects
				(font
					(size 1.27 1.27)
				)
				(justify mirror)
			)
		)
		(property "Value" ""
			(at 0 0 90)
			(layer "B.Fab")
			(effects
				(font
					(size 1.27 1.27)
				)
				(justify mirror)
			)
		)
		(duplicate_pad_numbers_are_jumpers no)
		(fp_line
			(start -0.7874 0.4064)
			(end 0.7874 0.4064)
			(stroke
				(width 0.1524)
				(type default)
			)
			(layer "B.SilkS")
		)
		(fp_line
			(start 0.7874 0.4064)
			(end 0.7874 -0.4064)
			(stroke
				(width 0.1524)
				(type default)
			)
			(layer "B.SilkS")
		)
		(fp_line
			(start -0.7874 -0.4064)
			(end -0.7874 0.4064)
			(stroke
				(width 0.1524)
				(type default)
			)
			(layer "B.SilkS")
		)
		(fp_line
			(start 0.7874 -0.4064)
			(end -0.7874 -0.4064)
			(stroke
				(width 0.1524)
				(type default)
			)
			(layer "B.SilkS")
		)
		(fp_line
			(start -0.67945 0.3048)
			(end -0.120396 0.3048)
			(stroke
				(width 0.1)
				(type default)
			)
			(layer "B.Fab")
		)
		(fp_line
			(start -0.120396 0.3048)
			(end -0.120396 0.2794)
			(stroke
				(width 0.1)
				(type default)
			)
			(layer "B.Fab")
		)
		(fp_line
			(start 0.12065 0.3048)
			(end 0.67945 0.3048)
			(stroke
				(width 0.1)
				(type default)
			)
			(layer "B.Fab")
		)
		(fp_line
			(start 0.67945 0.3048)
			(end 0.67945 -0.305054)
			(stroke
				(width 0.1)
				(type default)
			)
			(layer "B.Fab")
		)
		(fp_line
			(start -0.120396 0.2794)
			(end 0.12065 0.2794)
			(stroke
				(width 0.1)
				(type default)
			)
			(layer "B.Fab")
		)
		(fp_line
			(start 0.12065 0.2794)
			(end 0.12065 0.3048)
			(stroke
				(width 0.1)
				(type default)
			)
			(layer "B.Fab")
		)
		(fp_line
			(start -0.12065 -0.2794)
			(end -0.12065 -0.3048)
			(stroke
				(width 0.1)
				(type default)
			)
			(layer "B.Fab")
		)
		(fp_line
			(start 0.12065 -0.2794)
			(end -0.12065 -0.2794)
			(stroke
				(width 0.1)
				(type default)
			)
			(layer "B.Fab")
		)
		(fp_line
			(start -0.67945 -0.3048)
			(end -0.67945 0.3048)
			(stroke
				(width 0.1)
				(type default)
			)
			(layer "B.Fab")
		)
		(fp_line
			(start -0.12065 -0.3048)
			(end -0.67945 -0.3048)
			(stroke
				(width 0.1)
				(type default)
			)
			(layer "B.Fab")
		)
		(fp_line
			(start 0.12065 -0.305054)
			(end 0.12065 -0.2794)
			(stroke
				(width 0.1)
				(type default)
			)
			(layer "B.Fab")
		)
		(fp_line
			(start 0.67945 -0.305054)
			(end 0.12065 -0.305054)
			(stroke
				(width 0.1)
				(type default)
			)
			(layer "B.Fab")
		)
		(pad "1" smd circle
			(at 0.40005 0 90)
			(size 0 0)
			(layers "B.Cu" "B.Mask" "B.Paste")
			(net "PVCCIN_CPU1_PVCC")
		)
		(pad "2" smd circle
			(at -0.40005 0 90)
			(size 0 0)
			(layers "B.Cu" "B.Mask" "B.Paste")
			(net "PVCCIN_CPU1_VDD5")
		)
	)
	(footprint ""
		(layer "B.Cu")
		(at 104.49052 -326.994012 -90)
		(property "Reference" "PC590"
			(at 0 0 90)
			(layer "B.SilkS")
			(hide yes)
			(effects
				(font
					(size 1.27 1.27)
				)
				(justify mirror)
			)
		)
		(property "Value" ""
			(at 0 0 90)
			(layer "B.Fab")
			(effects
				(font
					(size 1.27 1.27)
				)
				(justify mirror)
			)
		)
		(duplicate_pad_numbers_are_jumpers no)
		(fp_line
			(start -4.533392 2.249932)
			(end 4.533392 2.249932)
			(stroke
				(width 0.1524)
				(type default)
			)
			(layer "B.SilkS")
		)
		(fp_line
			(start 4.533392 2.249932)
			(end 4.533392 -2.249932)
			(stroke
				(width 0.1524)
				(type default)
			)
			(layer "B.SilkS")
		)
		(fp_line
			(start -4.533392 -2.249932)
			(end -4.533392 2.249932)
			(stroke
				(width 0.1524)
				(type default)
			)
			(layer "B.SilkS")
		)
		(fp_line
			(start 4.533392 -2.249932)
			(end -4.533392 -2.249932)
			(stroke
				(width 0.1524)
				(type default)
			)
			(layer "B.SilkS")
		)
		(fp_rect
			(start 5.39242 2.326132)
			(end 4.533392 -2.326132)
			(stroke
				(width 0)
				(type default)
			)
			(fill yes)
			(layer "B.SilkS")
		)
		(fp_line
			(start -3.750056 2.249932)
			(end 3.750056 2.249932)
			(stroke
				(width 0.1)
				(type default)
			)
			(layer "B.Fab")
		)
		(fp_line
			(start 3.750056 2.249932)
			(end 3.750056 -2.249932)
			(stroke
				(width 0.1)
				(type default)
			)
			(layer "B.Fab")
		)
		(fp_line
			(start -3.750056 -2.249932)
			(end -3.750056 2.249932)
			(stroke
				(width 0.1)
				(type default)
			)
			(layer "B.Fab")
		)
		(fp_line
			(start 3.750056 -2.249932)
			(end -3.750056 -2.249932)
			(stroke
				(width 0.1)
				(type default)
			)
			(layer "B.Fab")
		)
		(fp_text user "+"
			(at 6.322314 0.786384 180)
			(unlocked yes)
			(layer "B.SilkS")
			(effects
				(font
					(size 1.905 1.4224)
					(thickness 0.1524)
				)
				(justify left mirror)
			)
		)
		(fp_text user "-"
			(at -4.575556 0.51435 270)
			(unlocked yes)
			(layer "B.SilkS")
			(effects
				(font
					(size 1.905 1.4224)
					(thickness 0.1524)
				)
				(justify left mirror)
			)
		)
		(fp_text user "+"
			(at 6.322314 0.786384 180)
			(unlocked yes)
			(layer "B.Fab")
			(effects
				(font
					(size 1.905 1.4224)
					(thickness 0.1524)
				)
				(justify left mirror)
			)
		)
		(fp_text user "-"
			(at -4.8514 -0.14605 270)
			(unlocked yes)
			(layer "B.Fab")
			(effects
				(font
					(size 1.905 1.4224)
					(thickness 0.1524)
				)
				(justify left mirror)
			)
		)
		(pad "1" smd rect
			(at 3.199892 0 90)
			(size 2.413 2.8194)
			(layers "B.Cu" "B.Mask" "B.Paste")
			(net "PVCCIN_CPU1")
		)
		(pad "2" smd rect
			(at -3.199892 0 90)
			(size 2.413 2.8194)
			(layers "B.Cu" "B.Mask" "B.Paste")
			(net "GND")
		)
	)
	(footprint ""
		(layer "B.Cu")
		(at 30.784546 -321.554856 -90)
		(property "Reference" "C67"
			(at 0 0 90)
			(layer "B.SilkS")
			(hide yes)
			(effects
				(font
					(size 1.27 1.27)
				)
				(justify mirror)
			)
		)
		(property "Value" ""
			(at 0 0 90)
			(layer "B.Fab")
			(effects
				(font
					(size 1.27 1.27)
				)
				(justify mirror)
			)
		)
		(duplicate_pad_numbers_are_jumpers no)
		(fp_line
			(start -1.524 0.762)
			(end 1.524 0.762)
			(stroke
				(width 0.1524)
				(type default)
			)
			(layer "B.SilkS")
		)
		(fp_line
			(start 1.524 0.762)
			(end 1.524 -0.762)
			(stroke
				(width 0.1524)
				(type default)
			)
			(layer "B.SilkS")
		)
		(fp_line
			(start -1.524 -0.762)
			(end -1.524 0.762)
			(stroke
				(width 0.1524)
				(type default)
			)
			(layer "B.SilkS")
		)
		(fp_line
			(start 1.524 -0.762)
			(end -1.524 -0.762)
			(stroke
				(width 0.1524)
				(type default)
			)
			(layer "B.SilkS")
		)
		(fp_line
			(start -1.1049 0.724916)
			(end -1.1049 -0.724916)
			(stroke
				(width 0.1)
				(type default)
			)
			(layer "B.Fab")
		)
		(fp_line
			(start 1.1049 0.724916)
			(end -1.1049 0.724916)
			(stroke
				(width 0.1)
				(type default)
			)
			(layer "B.Fab")
		)
		(fp_line
			(start -1.1049 -0.724916)
			(end 1.1049 -0.724916)
			(stroke
				(width 0.1)
				(type default)
			)
			(layer "B.Fab")
		)
		(fp_line
			(start 1.1049 -0.724916)
			(end 1.1049 0.724916)
			(stroke
				(width 0.1)
				(type default)
			)
			(layer "B.Fab")
		)
		(pad "1" smd rect
			(at 0.889 0 270)
			(size 1.016 1.27)
			(layers "B.Cu" "B.Mask" "B.Paste")
			(net "P12V_S3_AUX_CPU1_NVDIMM")
		)
		(pad "2" smd rect
			(at -0.889 0 270)
			(size 1.016 1.27)
			(layers "B.Cu" "B.Mask" "B.Paste")
			(net "GND")
		)
	)
	(footprint ""
		(layer "B.Cu")
		(at 114.427 -86.705948 180)
		(property "Reference" "R4022"
			(at 0 0 0)
			(layer "B.SilkS")
			(hide yes)
			(effects
				(font
					(size 1.27 1.27)
				)
				(justify mirror)
			)
		)
		(property "Value" ""
			(at 0 0 0)
			(layer "B.Fab")
			(effects
				(font
					(size 1.27 1.27)
				)
				(justify mirror)
			)
		)
		(duplicate_pad_numbers_are_jumpers no)
		(fp_line
			(start 0.7874 0.4064)
			(end 0.7874 -0.4064)
			(stroke
				(width 0.1524)
				(type default)
			)
			(layer "B.SilkS")
		)
		(fp_line
			(start 0.7874 -0.4064)
			(end -0.7874 -0.4064)
			(stroke
				(width 0.1524)
				(type default)
			)
			(layer "B.SilkS")
		)
		(fp_line
			(start -0.7874 0.4064)
			(end 0.7874 0.4064)
			(stroke
				(width 0.1524)
				(type default)
			)
			(layer "B.SilkS")
		)
		(fp_line
			(start -0.7874 -0.4064)
			(end -0.7874 0.4064)
			(stroke
				(width 0.1524)
				(type default)
			)
			(layer "B.SilkS")
		)
		(fp_line
			(start 0.67945 0.3048)
			(end 0.67945 -0.305054)
			(stroke
				(width 0.1)
				(type default)
			)
			(layer "B.Fab")
		)
		(fp_line
			(start 0.67945 -0.305054)
			(end 0.12065 -0.305054)
			(stroke
				(width 0.1)
				(type default)
			)
			(layer "B.Fab")
		)
		(fp_line
			(start 0.12065 0.3048)
			(end 0.67945 0.3048)
			(stroke
				(width 0.1)
				(type default)
			)
			(layer "B.Fab")
		)
		(fp_line
			(start 0.12065 0.2794)
			(end 0.12065 0.3048)
			(stroke
				(width 0.1)
				(type default)
			)
			(layer "B.Fab")
		)
		(fp_line
			(start 0.12065 -0.2794)
			(end -0.12065 -0.2794)
			(stroke
				(width 0.1)
				(type default)
			)
			(layer "B.Fab")
		)
		(fp_line
			(start 0.12065 -0.305054)
			(end 0.12065 -0.2794)
			(stroke
				(width 0.1)
				(type default)
			)
			(layer "B.Fab")
		)
		(fp_line
			(start -0.120396 0.3048)
			(end -0.120396 0.2794)
			(stroke
				(width 0.1)
				(type default)
			)
			(layer "B.Fab")
		)
		(fp_line
			(start -0.120396 0.2794)
			(end 0.12065 0.2794)
			(stroke
				(width 0.1)
				(type default)
			)
			(layer "B.Fab")
		)
		(fp_line
			(start -0.12065 -0.2794)
			(end -0.12065 -0.3048)
			(stroke
				(width 0.1)
				(type default)
			)
			(layer "B.Fab")
		)
		(fp_line
			(start -0.12065 -0.3048)
			(end -0.67945 -0.3048)
			(stroke
				(width 0.1)
				(type default)
			)
			(layer "B.Fab")
		)
		(fp_line
			(start -0.67945 0.3048)
			(end -0.120396 0.3048)
			(stroke
				(width 0.1)
				(type default)
			)
			(layer "B.Fab")
		)
		(fp_line
			(start -0.67945 -0.3048)
			(end -0.67945 0.3048)
			(stroke
				(width 0.1)
				(type default)
			)
			(layer "B.Fab")
		)
		(pad "1" smd circle
			(at 0.40005 0)
			(size 0 0)
			(layers "B.Cu" "B.Mask" "B.Paste")
			(net "H_CPU_RMCA_LVC2_R1_N")
		)
		(pad "2" smd circle
			(at -0.40005 0)
			(size 0 0)
			(layers "B.Cu" "B.Mask" "B.Paste")
			(net "H_CPU_RMCA_LVC2_R2_N")
		)
	)
	(footprint ""
		(layer "B.Cu")
		(at 257.32867 -102.28834 90)
		(property "Reference" "C119"
			(at 0 0 90)
			(layer "B.SilkS")
			(hide yes)
			(effects
				(font
					(size 1.27 1.27)
				)
				(justify mirror)
			)
		)
		(property "Value" ""
			(at 0 0 90)
			(layer "B.Fab")
			(effects
				(font
					(size 1.27 1.27)
				)
				(justify mirror)
			)
		)
		(duplicate_pad_numbers_are_jumpers no)
		(fp_line
			(start 0.7874 -0.4064)
			(end -0.7874 -0.4064)
			(stroke
				(width 0.1524)
				(type default)
			)
			(layer "B.SilkS")
		)
		(fp_line
			(start -0.7874 -0.4064)
			(end -0.7874 0.4064)
			(stroke
				(width 0.1524)
				(type default)
			)
			(layer "B.SilkS")
		)
		(fp_line
			(start 0.7874 0.4064)
			(end 0.7874 -0.4064)
			(stroke
				(width 0.1524)
				(type default)
			)
			(layer "B.SilkS")
		)
		(fp_line
			(start -0.7874 0.4064)
			(end 0.7874 0.4064)
			(stroke
				(width 0.1524)
				(type default)
			)
			(layer "B.SilkS")
		)
		(fp_line
			(start 0.67945 -0.305054)
			(end 0.12065 -0.305054)
			(stroke
				(width 0.1)
				(type default)
			)
			(layer "B.Fab")
		)
		(fp_line
			(start 0.12065 -0.305054)
			(end 0.12065 -0.2794)
			(stroke
				(width 0.1)
				(type default)
			)
			(layer "B.Fab")
		)
		(fp_line
			(start -0.12065 -0.3048)
			(end -0.67945 -0.3048)
			(stroke
				(width 0.1)
				(type default)
			)
			(layer "B.Fab")
		)
		(fp_line
			(start -0.67945 -0.3048)
			(end -0.67945 0.3048)
			(stroke
				(width 0.1)
				(type default)
			)
			(layer "B.Fab")
		)
		(fp_line
			(start 0.12065 -0.2794)
			(end -0.12065 -0.2794)
			(stroke
				(width 0.1)
				(type default)
			)
			(layer "B.Fab")
		)
		(fp_line
			(start -0.12065 -0.2794)
			(end -0.12065 -0.3048)
			(stroke
				(width 0.1)
				(type default)
			)
			(layer "B.Fab")
		)
		(fp_line
			(start 0.12065 0.2794)
			(end 0.12065 0.3048)
			(stroke
				(width 0.1)
				(type default)
			)
			(layer "B.Fab")
		)
		(fp_line
			(start -0.120396 0.2794)
			(end 0.12065 0.2794)
			(stroke
				(width 0.1)
				(type default)
			)
			(layer "B.Fab")
		)
		(fp_line
			(start 0.67945 0.3048)
			(end 0.67945 -0.305054)
			(stroke
				(width 0.1)
				(type default)
			)
			(layer "B.Fab")
		)
		(fp_line
			(start 0.12065 0.3048)
			(end 0.67945 0.3048)
			(stroke
				(width 0.1)
				(type default)
			)
			(layer "B.Fab")
		)
		(fp_line
			(start -0.120396 0.3048)
			(end -0.120396 0.2794)
			(stroke
				(width 0.1)
				(type default)
			)
			(layer "B.Fab")
		)
		(fp_line
			(start -0.67945 0.3048)
			(end -0.120396 0.3048)
			(stroke
				(width 0.1)
				(type default)
			)
			(layer "B.Fab")
		)
		(pad "1" smd circle
			(at 0.40005 0 270)
			(size 0 0)
			(layers "B.Cu" "B.Mask" "B.Paste")
			(net "P3V3_AUX_CLK_GEN_VDDMXCK_CK440")
		)
		(pad "2" smd circle
			(at -0.40005 0 270)
			(size 0 0)
			(layers "B.Cu" "B.Mask" "B.Paste")
			(net "GND")
		)
	)
)
